# S9S_MB_2U (Grand Teton) — schematic netlist excerpt (pin names and nets, part order shuffled) for the footprints in the layout excerpt that follows; sources: Cadence DE-HDL packaged netlist, KiCad conversion of 03242023_DA0F0TMBIJ0_F0T_Motherboard_J_brd_V01_OCP.brd

R4642  Q_RES  1K 1% EMPTY  pkg 0402LF  page 167 : A = P3V3_AUX ; B = FM_P2E_BUF2_VODB_DB
R4404  Q_RES  1.5K 1% CHIP  pkg 0402LF  page 122 : A = H_CPU1_MEMHOT_OUT ; B = H_CPU1_MEMHOT_OUT_R

(kicad_pcb
	(version 20260206)
	(generator "pcbnew")
	(generator_version "10.0")
	(general
		(thickness 1.6)
		(legacy_teardrops no)
	)
	(paper "A4")
	(title_block
		(title "03242023_DA0F0TMBIJ0_F0T_Motherboard_J_brd_V01_OCP.brd")
		(comment 1 "Grand Teton / footprints 3264-3265 of 6105")
	)
	(layers
		(0 "F.Cu" signal "TOP")
		(4 "In1.Cu" signal "GND")
		(6 "In2.Cu" signal "IN1")
		(8 "In3.Cu" signal "GND1")
		(10 "In4.Cu" signal "IN2")
		(12 "In5.Cu" signal "GND2")
		(14 "In6.Cu" signal "IN3")
		(16 "In7.Cu" signal "GND3")
		(18 "In8.Cu" signal "VCC")
		(20 "In9.Cu" signal "VCC1")
		(22 "In10.Cu" signal "GND4")
		(24 "In11.Cu" signal "IN4")
		(26 "In12.Cu" signal "GND5")
		(28 "In13.Cu" signal "IN5")
		(30 "In14.Cu" signal "GND6")
		(32 "In15.Cu" signal "IN6")
		(34 "In16.Cu" signal "GND7")
		(2 "B.Cu" signal "BOTTOM")
		(9 "F.Adhes" user "F.Adhesive")
		(11 "B.Adhes" user "B.Adhesive")
		(13 "F.Paste" user "Package Geometry/Pastemask Top")
		(15 "B.Paste" user "Package Geometry/Pastemask Bottom")
		(5 "F.SilkS" user "Ref Des/Silkscreen Top")
		(7 "B.SilkS" user "Ref Des/Silkscreen Bottom")
		(1 "F.Mask" user "Board Geometry/Soldermask Top")
		(3 "B.Mask" user "Board Geometry/Soldermask Bottom")
		(17 "Dwgs.User" user "User.Drawings")
		(19 "Cmts.User" user "User.Comments")
		(21 "Eco1.User" user "User.Eco1")
		(23 "Eco2.User" user "User.Eco2")
		(25 "Edge.Cuts" user "Board Geometry/Outline")
		(27 "Margin" user)
		(31 "F.CrtYd" user "Package Geometry/Place Bound Top")
		(29 "B.CrtYd" user "Package Geometry/Place Bound Bottom")
		(35 "F.Fab" user "Ref Des/Assembly Top")
		(33 "B.Fab" user "Ref Des/Assembly Bottom")
	)
	(footprint ""
		(layer "F.Cu")
		(at 49.324514 -394.44676 180)
		(property "Reference" "R4642"
			(at 0 0 180)
			(layer "F.SilkS")
			(hide yes)
			(effects
				(font
					(size 1.27 1.27)
				)
			)
		)
		(property "Value" ""
			(at 0 0 180)
			(layer "F.Fab")
			(effects
				(font
					(size 1.27 1.27)
				)
			)
		)
		(duplicate_pad_numbers_are_jumpers no)
		(fp_line
			(start 0.7874 0.4064)
			(end -0.7874 0.4064)
			(stroke
				(width 0.1524)
				(type default)
			)
			(layer "F.SilkS")
		)
		(fp_line
			(start 0.7874 -0.4064)
			(end 0.7874 0.4064)
			(stroke
				(width 0.1524)
				(type default)
			)
			(layer "F.SilkS")
		)
		(fp_line
			(start -0.7874 0.4064)
			(end -0.7874 -0.4064)
			(stroke
				(width 0.1524)
				(type default)
			)
			(layer "F.SilkS")
		)
		(fp_line
			(start -0.7874 -0.4064)
			(end 0.7874 -0.4064)
			(stroke
				(width 0.1524)
				(type default)
			)
			(layer "F.SilkS")
		)
		(fp_line
			(start 0.67945 0.3048)
			(end 0.120396 0.3048)
			(stroke
				(width 0.1)
				(type default)
			)
			(layer "F.Fab")
		)
		(fp_line
			(start 0.67945 -0.3048)
			(end 0.67945 0.3048)
			(stroke
				(width 0.1)
				(type default)
			)
			(layer "F.Fab")
		)
		(fp_line
			(start 0.12065 -0.2794)
			(end 0.12065 -0.3048)
			(stroke
				(width 0.1)
				(type default)
			)
			(layer "F.Fab")
		)
		(fp_line
			(start 0.12065 -0.3048)
			(end 0.67945 -0.3048)
			(stroke
				(width 0.1)
				(type default)
			)
			(layer "F.Fab")
		)
		(fp_line
			(start 0.120396 0.3048)
			(end 0.120396 0.2794)
			(stroke
				(width 0.1)
				(type default)
			)
			(layer "F.Fab")
		)
		(fp_line
			(start 0.120396 0.2794)
			(end -0.12065 0.2794)
			(stroke
				(width 0.1)
				(type default)
			)
			(layer "F.Fab")
		)
		(fp_line
			(start -0.12065 0.3048)
			(end -0.67945 0.3048)
			(stroke
				(width 0.1)
				(type default)
			)
			(layer "F.Fab")
		)
		(fp_line
			(start -0.12065 0.2794)
			(end -0.12065 0.3048)
			(stroke
				(width 0.1)
				(type default)
			)
			(layer "F.Fab")
		)
		(fp_line
			(start -0.12065 -0.2794)
			(end 0.12065 -0.2794)
			(stroke
				(width 0.1)
				(type default)
			)
			(layer "F.Fab")
		)
		(fp_line
			(start -0.12065 -0.305054)
			(end -0.12065 -0.2794)
			(stroke
				(width 0.1)
				(type default)
			)
			(layer "F.Fab")
		)
		(fp_line
			(start -0.67945 0.3048)
			(end -0.67945 -0.305054)
			(stroke
				(width 0.1)
				(type default)
			)
			(layer "F.Fab")
		)
		(fp_line
			(start -0.67945 -0.305054)
			(end -0.12065 -0.305054)
			(stroke
				(width 0.1)
				(type default)
			)
			(layer "F.Fab")
		)
		(pad "1" smd circle
			(at -0.40005 0 180)
			(size 0 0)
			(layers "F.Cu" "F.Mask" "F.Paste")
			(net "P3V3_AUX")
		)
		(pad "2" smd circle
			(at 0.40005 0 180)
			(size 0 0)
			(layers "F.Cu" "F.Mask" "F.Paste")
			(net "FM_P2E_BUF2_VODB_DB")
		)
	)
	(footprint ""
		(layer "F.Cu")
		(at 132.29082 -97.125028 90)
		(property "Reference" "R4404"
			(at 0 0 90)
			(layer "F.SilkS")
			(hide yes)
			(effects
				(font
					(size 1.27 1.27)
				)
			)
		)
		(property "Value" ""
			(at 0 0 90)
			(layer "F.Fab")
			(effects
				(font
					(size 1.27 1.27)
				)
			)
		)
		(duplicate_pad_numbers_are_jumpers no)
		(fp_line
			(start 0.7874 -0.4064)
			(end 0.7874 0.4064)
			(stroke
				(width 0.1524)
				(type default)
			)
			(layer "F.SilkS")
		)
		(fp_line
			(start -0.7874 -0.4064)
			(end 0.7874 -0.4064)
			(stroke
				(width 0.1524)
				(type default)
			)
			(layer "F.SilkS")
		)
		(fp_line
			(start 0.7874 0.4064)
			(end -0.7874 0.4064)
			(stroke
				(width 0.1524)
				(type default)
			)
			(layer "F.SilkS")
		)
		(fp_line
			(start -0.7874 0.4064)
			(end -0.7874 -0.4064)
			(stroke
				(width 0.1524)
				(type default)
			)
			(layer "F.SilkS")
		)
		(fp_line
			(start -0.12065 -0.305054)
			(end -0.12065 -0.2794)
			(stroke
				(width 0.1)
				(type default)
			)
			(layer "F.Fab")
		)
		(fp_line
			(start -0.67945 -0.305054)
			(end -0.12065 -0.305054)
			(stroke
				(width 0.1)
				(type default)
			)
			(layer "F.Fab")
		)
		(fp_line
			(start 0.67945 -0.3048)
			(end 0.67945 0.3048)
			(stroke
				(width 0.1)
				(type default)
			)
			(layer "F.Fab")
		)
		(fp_line
			(start 0.12065 -0.3048)
			(end 0.67945 -0.3048)
			(stroke
				(width 0.1)
				(type default)
			)
			(layer "F.Fab")
		)
		(fp_line
			(start 0.12065 -0.2794)
			(end 0.12065 -0.3048)
			(stroke
				(width 0.1)
				(type default)
			)
			(layer "F.Fab")
		)
		(fp_line
			(start -0.12065 -0.2794)
			(end 0.12065 -0.2794)
			(stroke
				(width 0.1)
				(type default)
			)
			(layer "F.Fab")
		)
		(fp_line
			(start 0.120396 0.2794)
			(end -0.12065 0.2794)
			(stroke
				(width 0.1)
				(type default)
			)
			(layer "F.Fab")
		)
		(fp_line
			(start -0.12065 0.2794)
			(end -0.12065 0.3048)
			(stroke
				(width 0.1)
				(type default)
			)
			(layer "F.Fab")
		)
		(fp_line
			(start 0.67945 0.3048)
			(end 0.120396 0.3048)
			(stroke
				(width 0.1)
				(type default)
			)
			(layer "F.Fab")
		)
		(fp_line
			(start 0.120396 0.3048)
			(end 0.120396 0.2794)
			(stroke
				(width 0.1)
				(type default)
			)
			(layer "F.Fab")
		)
		(fp_line
			(start -0.12065 0.3048)
			(end -0.67945 0.3048)
			(stroke
				(width 0.1)
				(type default)
			)
			(layer "F.Fab")
		)
		(fp_line
			(start -0.67945 0.3048)
			(end -0.67945 -0.305054)
			(stroke
				(width 0.1)
				(type default)
			)
			(layer "F.Fab")
		)
		(pad "1" smd circle
			(at -0.40005 0 90)
			(size 0 0)
			(layers "F.Cu" "F.Mask" "F.Paste")
			(net "H_CPU1_MEMHOT_OUT")
		)
		(pad "2" smd circle
			(at 0.40005 0 90)
			(size 0 0)
			(layers "F.Cu" "F.Mask" "F.Paste")
			(net "H_CPU1_MEMHOT_OUT_R")
		)
	)
)
